# S9S_MB_2U (Grand Teton) — schematic netlist excerpt (pin names and nets, part order shuffled) for the footprints in the layout excerpt that follows; sources: Cadence DE-HDL packaged netlist, KiCad conversion of 03242023_DA0F0TMBIJ0_F0T_Motherboard_J_brd_V01_OCP.brd

R1242  Q_RES  301 1% CHIP  pkg 0402LF  page 117 : A = PVNN_TERM_CPU0 ; B = H_CPU_PM_FAST_WAKE_N

X12  TP_TDR_4P_FTS  TP_TDR_4P_DIP EMPTY  pkg TH  page 309
  S1  = TDR_DIFF_85_BOT_DN
  P1  = T1_GND
  P2  = T1_GND
  S2  = TDR_DIFF_85_BOT_DP

(kicad_pcb
	(version 20260206)
	(generator "pcbnew")
	(generator_version "10.0")
	(general
		(thickness 1.6)
		(legacy_teardrops no)
	)
	(paper "A4")
	(title_block
		(title "03242023_DA0F0TMBIJ0_F0T_Motherboard_J_brd_V01_OCP.brd")
		(comment 1 "Grand Teton / footprints 5162-5163 of 6105")
	)
	(layers
		(0 "F.Cu" signal "TOP")
		(4 "In1.Cu" signal "GND")
		(6 "In2.Cu" signal "IN1")
		(8 "In3.Cu" signal "GND1")
		(10 "In4.Cu" signal "IN2")
		(12 "In5.Cu" signal "GND2")
		(14 "In6.Cu" signal "IN3")
		(16 "In7.Cu" signal "GND3")
		(18 "In8.Cu" signal "VCC")
		(20 "In9.Cu" signal "VCC1")
		(22 "In10.Cu" signal "GND4")
		(24 "In11.Cu" signal "IN4")
		(26 "In12.Cu" signal "GND5")
		(28 "In13.Cu" signal "IN5")
		(30 "In14.Cu" signal "GND6")
		(32 "In15.Cu" signal "IN6")
		(34 "In16.Cu" signal "GND7")
		(2 "B.Cu" signal "BOTTOM")
		(9 "F.Adhes" user "F.Adhesive")
		(11 "B.Adhes" user "B.Adhesive")
		(13 "F.Paste" user "Package Geometry/Pastemask Top")
		(15 "B.Paste" user "Package Geometry/Pastemask Bottom")
		(5 "F.SilkS" user "Ref Des/Silkscreen Top")
		(7 "B.SilkS" user "Ref Des/Silkscreen Bottom")
		(1 "F.Mask" user "Board Geometry/Soldermask Top")
		(3 "B.Mask" user "Board Geometry/Soldermask Bottom")
		(17 "Dwgs.User" user "User.Drawings")
		(19 "Cmts.User" user "User.Comments")
		(21 "Eco1.User" user "User.Eco1")
		(23 "Eco2.User" user "User.Eco2")
		(25 "Edge.Cuts" user "Board Geometry/Outline")
		(27 "Margin" user)
		(31 "F.CrtYd" user "Package Geometry/Place Bound Top")
		(29 "B.CrtYd" user "Package Geometry/Place Bound Bottom")
		(35 "F.Fab" user "Ref Des/Assembly Top")
		(33 "B.Fab" user "Ref Des/Assembly Bottom")
	)
	(footprint ""
		(layer "B.Cu")
		(at 381.213868 -189.29096)
		(property "Reference" "R1242"
			(at 0 0 0)
			(layer "B.SilkS")
			(hide yes)
			(effects
				(font
					(size 1.27 1.27)
				)
				(justify mirror)
			)
		)
		(property "Value" ""
			(at 0 0 0)
			(layer "B.Fab")
			(effects
				(font
					(size 1.27 1.27)
				)
				(justify mirror)
			)
		)
		(duplicate_pad_numbers_are_jumpers no)
		(fp_line
			(start -0.7874 -0.4064)
			(end -0.7874 0.4064)
			(stroke
				(width 0.1524)
				(type default)
			)
			(layer "B.SilkS")
		)
		(fp_line
			(start -0.7874 0.4064)
			(end 0.7874 0.4064)
			(stroke
				(width 0.1524)
				(type default)
			)
			(layer "B.SilkS")
		)
		(fp_line
			(start 0.7874 -0.4064)
			(end -0.7874 -0.4064)
			(stroke
				(width 0.1524)
				(type default)
			)
			(layer "B.SilkS")
		)
		(fp_line
			(start 0.7874 0.4064)
			(end 0.7874 -0.4064)
			(stroke
				(width 0.1524)
				(type default)
			)
			(layer "B.SilkS")
		)
		(fp_line
			(start -0.67945 -0.3048)
			(end -0.67945 0.3048)
			(stroke
				(width 0.1)
				(type default)
			)
			(layer "B.Fab")
		)
		(fp_line
			(start -0.67945 0.3048)
			(end -0.120396 0.3048)
			(stroke
				(width 0.1)
				(type default)
			)
			(layer "B.Fab")
		)
		(fp_line
			(start -0.12065 -0.3048)
			(end -0.67945 -0.3048)
			(stroke
				(width 0.1)
				(type default)
			)
			(layer "B.Fab")
		)
		(fp_line
			(start -0.12065 -0.2794)
			(end -0.12065 -0.3048)
			(stroke
				(width 0.1)
				(type default)
			)
			(layer "B.Fab")
		)
		(fp_line
			(start -0.120396 0.2794)
			(end 0.12065 0.2794)
			(stroke
				(width 0.1)
				(type default)
			)
			(layer "B.Fab")
		)
		(fp_line
			(start -0.120396 0.3048)
			(end -0.120396 0.2794)
			(stroke
				(width 0.1)
				(type default)
			)
			(layer "B.Fab")
		)
		(fp_line
			(start 0.12065 -0.305054)
			(end 0.12065 -0.2794)
			(stroke
				(width 0.1)
				(type default)
			)
			(layer "B.Fab")
		)
		(fp_line
			(start 0.12065 -0.2794)
			(end -0.12065 -0.2794)
			(stroke
				(width 0.1)
				(type default)
			)
			(layer "B.Fab")
		)
		(fp_line
			(start 0.12065 0.2794)
			(end 0.12065 0.3048)
			(stroke
				(width 0.1)
				(type default)
			)
			(layer "B.Fab")
		)
		(fp_line
			(start 0.12065 0.3048)
			(end 0.67945 0.3048)
			(stroke
				(width 0.1)
				(type default)
			)
			(layer "B.Fab")
		)
		(fp_line
			(start 0.67945 -0.305054)
			(end 0.12065 -0.305054)
			(stroke
				(width 0.1)
				(type default)
			)
			(layer "B.Fab")
		)
		(fp_line
			(start 0.67945 0.3048)
			(end 0.67945 -0.305054)
			(stroke
				(width 0.1)
				(type default)
			)
			(layer "B.Fab")
		)
		(pad "1" smd circle
			(at 0.40005 0 180)
			(size 0 0)
			(layers "B.Cu" "B.Mask" "B.Paste")
			(net "PVNN_TERM_CPU0")
		)
		(pad "2" smd circle
			(at -0.40005 0 180)
			(size 0 0)
			(layers "B.Cu" "B.Mask" "B.Paste")
			(net "H_CPU_PM_FAST_WAKE_N")
		)
	)
	(footprint ""
		(layer "B.Cu")
		(at 490.57433 -303.547272 -90)
		(property "Reference" "X12"
			(at 3.322828 3.706876 270)
			(unlocked yes)
			(layer "B.SilkS")
			(effects
				(font
					(size 0.7874 0.5842)
					(thickness 0.1524)
				)
				(justify left mirror)
			)
		)
		(property "Value" ""
			(at 0 0 90)
			(layer "B.Fab")
			(effects
				(font
					(size 1.27 1.27)
				)
				(justify mirror)
			)
		)
		(property "Device Type" "TP_TDR_4P_FTS_MPKT4_H025P0200_I"
			(at -1.30175 1.27 180)
			(unlocked yes)
			(layer "B.Fab")
			(hide yes)
			(effects
				(font
					(size 0.635 0.4064)
					(thickness 0.1524)
				)
				(justify mirror)
			)
		)
		(property "User Part Number" "TP15"
			(at -1.30175 1.27 180)
			(unlocked yes)
			(layer "Cmts.User")
			(hide yes)
			(effects
				(font
					(size 0.635 0.4064)
					(thickness 0.1524)
				)
				(justify mirror)
			)
		)
		(duplicate_pad_numbers_are_jumpers no)
		(fp_line
			(start -2.54 3.81)
			(end -2.54 3.6703)
			(stroke
				(width 0.1524)
				(type default)
			)
			(layer "B.SilkS")
		)
		(fp_line
			(start 0 3.81)
			(end -2.54 3.81)
			(stroke
				(width 0.1524)
				(type default)
			)
			(layer "B.SilkS")
		)
		(fp_line
			(start 0 3.175)
			(end 0 3.81)
			(stroke
				(width 0.1524)
				(type default)
			)
			(layer "B.SilkS")
		)
		(fp_line
			(start -2.54 1.4097)
			(end -2.54 1.1303)
			(stroke
				(width 0.1524)
				(type default)
			)
			(layer "B.SilkS")
		)
		(fp_line
			(start 0 0.635)
			(end 0 1.905)
			(stroke
				(width 0.1524)
				(type default)
			)
			(layer "B.SilkS")
		)
		(fp_line
			(start -2.54 -1.1303)
			(end -2.54 -1.27)
			(stroke
				(width 0.1524)
				(type default)
			)
			(layer "B.SilkS")
		)
		(fp_line
			(start -2.54 -1.27)
			(end 0 -1.27)
			(stroke
				(width 0.1524)
				(type default)
			)
			(layer "B.SilkS")
		)
		(fp_line
			(start 0 -1.27)
			(end 0 -0.635)
			(stroke
				(width 0.1524)
				(type default)
			)
			(layer "B.SilkS")
		)
		(fp_poly
			(pts
				(xy 2.853944 -0.825246) (xy 2.853944 0.698754) (xy 1.329944 -0.063246)
			)
			(stroke
				(width 0)
				(type default)
			)
			(fill yes)
			(layer "B.SilkS")
		)
		(fp_line
			(start -2.54 3.81)
			(end -2.54 -1.27)
			(stroke
				(width 0.1)
				(type default)
			)
			(layer "B.Fab")
		)
		(fp_line
			(start 0 3.81)
			(end -2.54 3.81)
			(stroke
				(width 0.1)
				(type default)
			)
			(layer "B.Fab")
		)
		(fp_line
			(start -2.54 -1.27)
			(end 0 -1.27)
			(stroke
				(width 0.1)
				(type default)
			)
			(layer "B.Fab")
		)
		(fp_line
			(start 0 -1.27)
			(end 0 3.81)
			(stroke
				(width 0.1)
				(type default)
			)
			(layer "B.Fab")
		)
		(fp_poly
			(pts
				(xy 0.761746 0) (xy 2.285746 -0.762) (xy 2.285746 0.762)
			)
			(stroke
				(width 0)
				(type default)
			)
			(fill yes)
			(layer "B.Fab")
		)
		(pad "1" thru_hole circle
			(at 0 0 90)
			(size 1.0033 1.0033)
			(drill 0.249936)
			(layers "*.Cu" "*.Mask")
			(remove_unused_layers no)
			(net "TDR_DIFF_85_BOT_DN")
			(clearance 0.10795)
			(padstack
				(mode front_inner_back)
				(layer "Inner"
					(shape circle)
					(size 0.8001 0.8001)
					(clearance 0.1524)
				)
				(layer "B.Cu"
					(shape circle)
					(size 1.0033 1.0033)
					(thermal_gap 0.10795)
					(clearance 0.10795)
				)
			)
		)
		(pad "2" thru_hole circle
			(at -2.54 0 90)
			(size 1.9939 1.9939)
			(drill 0.249936)
			(layers "*.Cu" "*.Mask")
			(remove_unused_layers no)
			(net "T1_GND")
			(clearance 0.10795)
			(padstack
				(mode front_inner_back)
				(layer "Inner"
					(shape circle)
					(size 0.8001 0.8001)
					(clearance 0.1524)
				)
				(layer "B.Cu"
					(shape circle)
					(size 1.9939 1.9939)
					(thermal_gap 0.10795)
					(clearance 0.10795)
				)
			)
		)
		(pad "3" thru_hole circle
			(at -2.54 2.54 90)
			(size 1.9939 1.9939)
			(drill 0.249936)
			(layers "*.Cu" "*.Mask")
			(remove_unused_layers no)
			(net "T1_GND")
			(clearance 0.10795)
			(padstack
				(mode front_inner_back)
				(layer "Inner"
					(shape circle)
					(size 0.8001 0.8001)
					(clearance 0.1524)
				)
				(layer "B.Cu"
					(shape circle)
					(size 1.9939 1.9939)
					(thermal_gap 0.10795)
					(clearance 0.10795)
				)
			)
		)
		(pad "4" thru_hole circle
			(at 0 2.54 90)
			(size 1.0033 1.0033)
			(drill 0.249936)
			(layers "*.Cu" "*.Mask")
			(remove_unused_layers no)
			(net "TDR_DIFF_85_BOT_DP")
			(clearance 0.10795)
			(padstack
				(mode front_inner_back)
				(layer "Inner"
					(shape circle)
					(size 0.8001 0.8001)
					(clearance 0.1524)
				)
				(layer "B.Cu"
					(shape circle)
					(size 1.0033 1.0033)
					(thermal_gap 0.10795)
					(clearance 0.10795)
				)
			)
		)
	)
)
